FILE_TYPE = MACRO_DRAWING;
SET COLOR_WIRE YELLOW;
SET COLOR_PROP MONO;
SET COLOR_DOT WHITE;
SET COLOR_ARC YELLOW;
SET COLOR_BODY GREEN;
SET COLOR_NOTE MONO;
SET PROP_DISPLAY VALUE;
SET PAGE_NUMBER P238;
FORCEADD OFFPAGE..1
(-2625 2500);
FORCEPROP 2 LAST $XR0 239 
J 0
(-2907 2500);
DISPLAY 0.638298 (-2907 2500);
PAINT MONO (-2907 2500);
FORCEPROP 1 LAST COMMENT_BODY TRUE
J 0
(-2500 2400);
DISPLAY 1.170213 (-2500 2400);
PAINT PEACH (-2500 2400);
DISPLAY INVISIBLE (-2500 2400);
FORCEPROP 1 LAST OFFPAGE TRUE
J 0
(-2300 2375);
PAINT GREEN (-2300 2375);
DISPLAY INVISIBLE (-2300 2375);
FORCEPROP 2 LAST ROOM P1V26_BMC_STBY_VR
J 0
(-3100 2575);
DISPLAY 1.340426 (-3100 2575);
PAINT GREEN (-3100 2575);
DISPLAY INVISIBLE (-3100 2575);
FORCEPROP 2 LAST CDS_LIB mstr_standard
J 0
(-2625 2500);
DISPLAY 1.340426 (-2625 2500);
PAINT ORANGE (-2625 2500);
DISPLAY INVISIBLE (-2625 2500);
FORCEPROP 2 LAST BOM_COST P1V26_BMC_STBY_VR
J 0
(-2900 2550);
PAINT WHITE (-2900 2550);
DISPLAY INVISIBLE (-2900 2550);
FORCEPROP 2 LAST PATH I1
J 0
(-2551 2574);
DISPLAY 1.021277 (-2551 2574);
PAINT ORANGE (-2551 2574);
DISPLAY INVISIBLE (-2551 2574);
FORCEADD GND..1
(1025 1850);
FORCEPROP 3 LASTPIN (1025 1900) SIG_NAME GND\g
J 0
(1035 1910);
DISPLAY 0.659574 (1035 1910);
PAINT MONO (1035 1910);
DISPLAY INVISIBLE (1035 1910);
FORCEPROP 2 LAST P1V5_STBY_IBMC_VR 
J 0
(1050 1925);
PAINT GREEN (1050 1925);
FORCEPROP 2 LAST P1V5_STBY_IBMC 
J 0
(1050 1975);
PAINT GREEN (1050 1975);
FORCEPROP 1 LAST HDL_POWER GND
J 0
(1025 2000);
DISPLAY 0.872340 (1025 2000);
PAINT GREEN (1025 2000);
DISPLAY INVISIBLE (1025 2000);
FORCEPROP 1 LAST BODY_TYPE PLUMBING
J 0
(980 1807);
DISPLAY 0.340426 (980 1807);
PAINT GREEN (980 1807);
DISPLAY INVISIBLE (980 1807);
FORCEPROP 2 LAST ROOM P1V26_BMC_STBY_VR
J 0
(675 1925);
DISPLAY 0.872340 (675 1925);
PAINT GREEN (675 1925);
DISPLAY INVISIBLE (675 1925);
FORCEPROP 1 LAST VOLTAGE 0.0V
J 0
(980 1807);
DISPLAY 0.340426 (980 1807);
PAINT SKYBLUE (980 1807);
DISPLAY INVISIBLE (980 1807);
FORCEPROP 2 LAST CDS_LIB mstr_symbols
J 0
(1025 1850);
PAINT ORANGE (1025 1850);
DISPLAY INVISIBLE (1025 1850);
FORCEPROP 1 LAST SIZE 1B
J 0
(1100 1800);
DISPLAY 0.872340 (1100 1800);
PAINT ORANGE (1100 1800);
DISPLAY INVISIBLE (1100 1800);
FORCEPROP 1 LAST PATH I13
J 0
(1100 1850);
DISPLAY 0.872340 (1100 1850);
PAINT AQUA (1100 1850);
DISPLAY INVISIBLE (1100 1850);
FORCEPROP 2 LAST BOM_COST P1V26_BMC_STBY_VR
J 0
(1050 2025);
PAINT WHITE (1050 2025);
DISPLAY INVISIBLE (1050 2025);
FORCEADD RES..1
R 1
(1025 2100);
FORCEPROP 1 LASTPIN (1025 2000) $PN 1
R 1
J 0
(1013 2012);
DISPLAY 0.617021 (1013 2012);
PAINT ORANGE (1013 2012);
FORCEPROP 1 LAST VALUE 10.0K
R 1
J 2
(1125 2075);
DISPLAY 0.617021 (1125 2075);
PAINT SKYBLUE (1125 2075);
FORCEPROP 1 LAST WATTAGE 1/16W
R 1
J 2
(1175 2075);
DISPLAY 0.617021 (1175 2075);
PAINT SKYBLUE (1175 2075);
FORCEPROP 1 LASTPIN (1025 2200) $PN 2
R 1
J 0
(1013 2162);
DISPLAY 0.617021 (1013 2162);
PAINT ORANGE (1013 2162);
FORCEPROP 1 LAST MATERIAL CHIP
R 1
J 0
(1175 2100);
DISPLAY 0.617021 (1175 2100);
PAINT SKYBLUE (1175 2100);
FORCEPROP 1 LAST PART_NUMBER G21796-016
R 1
J 0
(1225 1950);
DISPLAY 0.617021 (1225 1950);
PAINT BLUE (1225 1950);
FORCEPROP 1 LAST PACK_TYPE 0402
R 1
J 0
(1275 2000);
DISPLAY 0.617021 (1275 2000);
PAINT SKYBLUE (1275 2000);
FORCEPROP 1 LAST LOCATION R9F8
J 0
(1075 2225);
DISPLAY 0.617021 (1075 2225);
PAINT AQUA (1075 2225);
FORCEPROP 2 LAST P1V5_STBY_IBMC_VR 
J 0
(1075 2300);
PAINT GREEN (1075 2300);
FORCEPROP 2 LAST P1V5_STBY_IBMC 
J 0
(1075 2350);
PAINT GREEN (1075 2350);
FORCEPROP 1 LAST TOLERANCE 1%
R 1
J 0
(1125 2100);
DISPLAY 0.617021 (1125 2100);
PAINT SKYBLUE (1125 2100);
FORCEPROP 1 LAST PATH I14
R 1
J 0
(875 2050);
DISPLAY 0.978723 (875 2050);
PAINT WHITE (875 2050);
DISPLAY INVISIBLE (875 2050);
FORCEPROP 2 LAST ROOM P1V26_BMC_STBY_VR
J 0
(1075 2250);
PAINT GREEN (1075 2250);
DISPLAY INVISIBLE (1075 2250);
FORCEPROP 2 LAST CDS_LOCATION R9F8
J 0
(1075 2225);
DISPLAY 0.617021 (1075 2225);
PAINT AQUA (1075 2225);
DISPLAY INVISIBLE (1075 2225);
FORCEPROP 2 LAST CDS_LIB mstr_discrete
J 0
(1025 2100);
PAINT ORANGE (1025 2100);
DISPLAY INVISIBLE (1025 2100);
FORCEPROP 2 LAST SEC_TYPE 0402
J 0
(1075 2400);
DISPLAY 1.021277 (1075 2400);
PAINT ORANGE (1075 2400);
DISPLAY INVISIBLE (1075 2400);
FORCEPROP 2 LAST BOM_COST P1V26_BMC_STBY_VR
J 0
(1075 2400);
PAINT WHITE (1075 2400);
DISPLAY INVISIBLE (1075 2400);
FORCEPROP 2 LAST SEC 1
J 0
(1075 2400);
DISPLAY 0.680851 (1075 2400);
PAINT MONO (1075 2400);
DISPLAY INVISIBLE (1075 2400);
FORCEADD GND..1
(400 2200);
FORCEPROP 3 LASTPIN (400 2250) SIG_NAME GND\g
J 0
(410 2260);
DISPLAY 0.659574 (410 2260);
PAINT MONO (410 2260);
DISPLAY INVISIBLE (410 2260);
FORCEPROP 2 LAST P1V5_STBY_IBMC_VR 
J 0
(425 2275);
PAINT GREEN (425 2275);
FORCEPROP 2 LAST P1V5_STBY_IBMC 
J 0
(425 2325);
PAINT GREEN (425 2325);
FORCEPROP 1 LAST HDL_POWER GND
J 0
(400 2350);
DISPLAY 0.872340 (400 2350);
PAINT GREEN (400 2350);
DISPLAY INVISIBLE (400 2350);
FORCEPROP 1 LAST BODY_TYPE PLUMBING
J 0
(355 2157);
DISPLAY 0.340426 (355 2157);
PAINT GREEN (355 2157);
DISPLAY INVISIBLE (355 2157);
FORCEPROP 2 LAST ROOM P1V26_BMC_STBY_VR
J 0
(50 2275);
DISPLAY 0.872340 (50 2275);
PAINT GREEN (50 2275);
DISPLAY INVISIBLE (50 2275);
FORCEPROP 1 LAST PATH I15
J 0
(475 2200);
DISPLAY 0.872340 (475 2200);
PAINT AQUA (475 2200);
DISPLAY INVISIBLE (475 2200);
FORCEPROP 1 LAST SIZE 1B
J 0
(475 2150);
DISPLAY 0.872340 (475 2150);
PAINT ORANGE (475 2150);
DISPLAY INVISIBLE (475 2150);
FORCEPROP 2 LAST CDS_LIB mstr_symbols
J 0
(400 2200);
PAINT ORANGE (400 2200);
DISPLAY INVISIBLE (400 2200);
FORCEPROP 1 LAST VOLTAGE 0.0V
J 0
(355 2157);
DISPLAY 0.340426 (355 2157);
PAINT SKYBLUE (355 2157);
DISPLAY INVISIBLE (355 2157);
FORCEPROP 2 LAST BOM_COST P1V26_BMC_STBY_VR
J 0
(425 2375);
PAINT WHITE (425 2375);
DISPLAY INVISIBLE (425 2375);
FORCEADD CAP..1
(1250 3050);
FORCEPROP 1 LASTPIN (1250 2950) $PN 2
J 0
(1260 2930);
DISPLAY 0.617021 (1260 2930);
PAINT WHITE (1260 2930);
FORCEPROP 1 LAST MATERIAL X7R
J 0
(1300 2950);
DISPLAY 0.617021 (1300 2950);
PAINT SKYBLUE (1300 2950);
FORCEPROP 1 LAST TOLERANCE 10%
J 0
(1300 3000);
DISPLAY 0.617021 (1300 3000);
PAINT SKYBLUE (1300 3000);
FORCEPROP 1 LAST PART_NUMBER A36096-046
J 0
(1300 2900);
DISPLAY 0.617021 (1300 2900);
PAINT BLUE (1300 2900);
FORCEPROP 1 LASTPIN (1250 3150) $PN 1
J 0
(1260 3130);
DISPLAY 0.617021 (1260 3130);
PAINT WHITE (1260 3130);
FORCEPROP 1 LAST VALUE 1000PF
J 0
(1300 3100);
DISPLAY 0.617021 (1300 3100);
PAINT SKYBLUE (1300 3100);
FORCEPROP 1 LAST LOCATION C9F8
J 0
(1300 3150);
DISPLAY 0.617021 (1300 3150);
PAINT AQUA (1300 3150);
FORCEPROP 1 LAST PACK_TYPE 0402LF
J 0
(1300 2850);
DISPLAY 0.617021 (1300 2850);
PAINT SKYBLUE (1300 2850);
FORCEPROP 2 LAST CDS_LIB mstr_discrete
J 0
(1250 3050);
DISPLAY 1.617021 (1250 3050);
PAINT MONO (1250 3050);
DISPLAY INVISIBLE (1250 3050);
FORCEPROP 1 LAST VOLTAGE 50V
J 0
(1300 3050);
DISPLAY 1.617021 (1300 3050);
PAINT SKYBLUE (1300 3050);
DISPLAY INVISIBLE (1300 3050);
FORCEPROP 2 LAST ROOM P1V26_BMC_STBY_VR
J 0
(1310 3190);
DISPLAY 1.617021 (1310 3190);
PAINT GREEN (1310 3190);
DISPLAY INVISIBLE (1310 3190);
FORCEPROP 1 LAST PATH I19
J 0
(1300 3200);
DISPLAY 0.978723 (1300 3200);
PAINT WHITE (1300 3200);
DISPLAY INVISIBLE (1300 3200);
FORCEPROP 2 LAST CDS_LOCATION C9F8
J 0
(1300 3150);
DISPLAY 0.617021 (1300 3150);
PAINT AQUA (1300 3150);
DISPLAY INVISIBLE (1300 3150);
FORCEPROP 2 LAST $SEC 1
J 0
(1310 3265);
DISPLAY 1.617021 (1310 3265);
PAINT MONO (1310 3265);
DISPLAY INVISIBLE (1310 3265);
FORCEPROP 2 LAST CDS_SEC 1
J 0
(1310 3265);
DISPLAY 1.617021 (1310 3265);
PAINT MONO (1310 3265);
DISPLAY INVISIBLE (1310 3265);
FORCEPROP 2 LAST BOM_COST P1V26_BMC_STBY_VR
J 0
(1310 3190);
DISPLAY 1.617021 (1310 3190);
PAINT WHITE (1310 3190);
DISPLAY INVISIBLE (1310 3190);
FORCEADD GND..1
(1250 2825);
FORCEPROP 3 LASTPIN (1250 2875) SIG_NAME GND\g
J 0
(1260 2885);
DISPLAY 0.659574 (1260 2885);
PAINT MONO (1260 2885);
DISPLAY INVISIBLE (1260 2885);
FORCEPROP 1 LAST HDL_POWER GND
J 0
(1250 2975);
DISPLAY 1.063830 (1250 2975);
PAINT GREEN (1250 2975);
DISPLAY INVISIBLE (1250 2975);
FORCEPROP 1 LAST BODY_TYPE PLUMBING
J 0
(1205 2782);
DISPLAY 0.340426 (1205 2782);
PAINT GREEN (1205 2782);
DISPLAY INVISIBLE (1205 2782);
FORCEPROP 2 LAST ROOM P1V26_BMC_STBY_VR
J 0
(600 2900);
DISPLAY 1.212766 (600 2900);
PAINT GREEN (600 2900);
DISPLAY INVISIBLE (600 2900);
FORCEPROP 2 LAST BOM_COST P1V26_BMC_STBY_VR
J 0
(935 2915);
DISPLAY 1.617021 (935 2915);
PAINT WHITE (935 2915);
DISPLAY INVISIBLE (935 2915);
FORCEPROP 1 LAST VOLTAGE 0.0V
J 0
(1205 2782);
DISPLAY 0.340426 (1205 2782);
PAINT SKYBLUE (1205 2782);
DISPLAY INVISIBLE (1205 2782);
FORCEPROP 2 LAST CDS_LIB mstr_symbols
J 0
(1250 2825);
DISPLAY 1.617021 (1250 2825);
PAINT MONO (1250 2825);
DISPLAY INVISIBLE (1250 2825);
FORCEPROP 1 LAST PATH I20
J 0
(1325 2825);
DISPLAY 0.872340 (1325 2825);
PAINT AQUA (1325 2825);
DISPLAY INVISIBLE (1325 2825);
FORCEPROP 1 LAST SIZE 1B
J 0
(1325 2775);
DISPLAY 1.063830 (1325 2775);
PAINT GREEN (1325 2775);
DISPLAY INVISIBLE (1325 2775);
FORCEADD RES..2
(900 3500);
FORCEPROP 1 LASTPIN (900 3400) $PN 2
J 0
(905 3410);
DISPLAY 0.617021 (905 3410);
PAINT WHITE (905 3410);
FORCEPROP 1 LAST TOLERANCE 1%
J 0
(945 3525);
DISPLAY 0.617021 (945 3525);
PAINT SKYBLUE (945 3525);
FORCEPROP 1 LASTPIN (900 3600) $PN 1
J 0
(905 3562);
DISPLAY 0.617021 (905 3562);
PAINT WHITE (905 3562);
FORCEPROP 2 LAST P1V5_STBY_IBMC_VR 
J 0
(850 3650);
PAINT GREEN (850 3650);
FORCEPROP 2 LAST P1V5_STBY_IBMC 
J 0
(850 3700);
PAINT GREEN (850 3700);
FORCEPROP 1 LAST WATTAGE 1/16W
J 0
(940 3475);
DISPLAY 0.617021 (940 3475);
PAINT SKYBLUE (940 3475);
FORCEPROP 1 LAST MATERIAL CHIP
J 0
(940 3425);
DISPLAY 0.617021 (940 3425);
PAINT SKYBLUE (940 3425);
FORCEPROP 1 LAST PACK_TYPE 0402
J 0
(940 3325);
DISPLAY 0.617021 (940 3325);
PAINT SKYBLUE (940 3325);
FORCEPROP 1 LAST PART_NUMBER G21796-016
J 0
(940 3375);
DISPLAY 0.617021 (940 3375);
PAINT BLUE (940 3375);
FORCEPROP 1 LAST LOCATION R9F13
J 0
(945 3625);
DISPLAY 0.617021 (945 3625);
PAINT AQUA (945 3625);
FORCEPROP 1 LAST VALUE 10.0K
J 0
(945 3575);
DISPLAY 0.617021 (945 3575);
PAINT SKYBLUE (945 3575);
FORCEPROP 2 LAST CDS_LIB mstr_discrete
J 0
(900 3500);
PAINT ORANGE (900 3500);
DISPLAY INVISIBLE (900 3500);
FORCEPROP 2 LAST ROOM P1V26_BMC_STBY_VR
J 0
(850 3600);
PAINT GREEN (850 3600);
DISPLAY INVISIBLE (850 3600);
FORCEPROP 2 LAST BOM_COST P1V26_BMC_STBY_VR
J 0
(850 3750);
PAINT WHITE (850 3750);
DISPLAY INVISIBLE (850 3750);
FORCEPROP 2 LAST SEC_TYPE 0402
J 0
(850 3750);
DISPLAY 1.659574 (850 3750);
PAINT ORANGE (850 3750);
DISPLAY INVISIBLE (850 3750);
FORCEPROP 2 LAST SEC 1
J 0
(850 3750);
DISPLAY 1.106383 (850 3750);
PAINT MONO (850 3750);
DISPLAY INVISIBLE (850 3750);
FORCEPROP 2 LAST CDS_LOCATION R9F13
J 0
(945 3625);
DISPLAY 0.617021 (945 3625);
PAINT AQUA (945 3625);
DISPLAY INVISIBLE (945 3625);
FORCEPROP 1 LAST PATH I21
J 0
(950 3675);
DISPLAY 0.978723 (950 3675);
PAINT WHITE (950 3675);
DISPLAY INVISIBLE (950 3675);
FORCEADD P3V3_STBY..1
(900 3825);
FORCEPROP 3 LASTPIN (900 3775) SIG_NAME P3V3_STBY\g
J 0
(910 3785);
DISPLAY 0.659574 (910 3785);
PAINT MONO (910 3785);
DISPLAY INVISIBLE (910 3785);
FORCEPROP 1 LAST HDL_POWER P3V3_STBY
J 0
(600 3700);
DISPLAY 0.872340 (600 3700);
PAINT ORANGE (600 3700);
DISPLAY INVISIBLE (600 3700);
FORCEPROP 1 LAST BODY_TYPE PLUMBING
J 0
(855 3782);
DISPLAY 0.340426 (855 3782);
PAINT GREEN (855 3782);
DISPLAY INVISIBLE (855 3782);
FORCEPROP 2 LAST CDS_LIB mstr_symbols
J 0
(900 3825);
PAINT ORANGE (900 3825);
DISPLAY INVISIBLE (900 3825);
FORCEPROP 1 LAST PATH I22
J 0
(945 3827);
DISPLAY 0.340426 (945 3827);
PAINT GREEN (945 3827);
DISPLAY INVISIBLE (945 3827);
FORCEPROP 1 LAST VOLTAGE 3.3V
J 0
(855 3782);
DISPLAY 0.340426 (855 3782);
PAINT SKYBLUE (855 3782);
DISPLAY INVISIBLE (855 3782);
FORCEPROP 1 LAST SIZE 1B
J 0
(945 3847);
DISPLAY 0.340426 (945 3847);
PAINT GREEN (945 3847);
DISPLAY INVISIBLE (945 3847);
FORCEADD CAP..1
(1950 2525);
FORCEPROP 1 LASTPIN (1950 2425) $PN 2
J 0
(1960 2405);
DISPLAY 0.617021 (1960 2405);
PAINT WHITE (1960 2405);
FORCEPROP 1 LAST PART_NUMBER E15431-002
J 0
(2000 2375);
DISPLAY 0.617021 (2000 2375);
PAINT BLUE (2000 2375);
FORCEPROP 1 LAST LOCATION C9E10
J 0
(2000 2625);
DISPLAY 0.617021 (2000 2625);
PAINT AQUA (2000 2625);
FORCEPROP 1 LAST VALUE 10UF
J 0
(2000 2575);
DISPLAY 0.617021 (2000 2575);
PAINT SKYBLUE (2000 2575);
FORCEPROP 1 LAST TOLERANCE 20%
J 0
(2000 2475);
DISPLAY 0.617021 (2000 2475);
PAINT SKYBLUE (2000 2475);
FORCEPROP 1 LASTPIN (1950 2625) $PN 1
J 0
(1960 2605);
DISPLAY 0.617021 (1960 2605);
PAINT WHITE (1960 2605);
FORCEPROP 1 LAST VOLTAGE 6.3V
J 0
(2000 2525);
DISPLAY 0.617021 (2000 2525);
PAINT SKYBLUE (2000 2525);
FORCEPROP 1 LAST MATERIAL X6S
J 0
(2000 2425);
DISPLAY 0.617021 (2000 2425);
PAINT SKYBLUE (2000 2425);
FORCEPROP 1 LAST PACK_TYPE 0603
J 0
(2000 2325);
DISPLAY 0.617021 (2000 2325);
PAINT SKYBLUE (2000 2325);
FORCEPROP 2 LAST CDS_LIB mstr_discrete
J 0
(1950 2525);
PAINT ORANGE (1950 2525);
DISPLAY INVISIBLE (1950 2525);
FORCEPROP 2 LAST CDS_LOCATION C9E10
J 0
(2000 2625);
DISPLAY 0.617021 (2000 2625);
PAINT AQUA (2000 2625);
DISPLAY INVISIBLE (2000 2625);
FORCEPROP 1 LAST PATH I23
J 0
(2000 2675);
DISPLAY 0.978723 (2000 2675);
PAINT WHITE (2000 2675);
DISPLAY INVISIBLE (2000 2675);
FORCEPROP 2 LAST BOM_COST P1V26_BMC_STBY_VR
J 0
(2000 2675);
PAINT WHITE (2000 2675);
DISPLAY INVISIBLE (2000 2675);
FORCEPROP 2 LAST SEC 1
J 0
(2000 2725);
DISPLAY 1.106383 (2000 2725);
PAINT MONO (2000 2725);
DISPLAY INVISIBLE (2000 2725);
FORCEPROP 2 LAST ROOM P1V26_BMC_STBY_VR
J 0
(2000 2725);
PAINT GREEN (2000 2725);
DISPLAY INVISIBLE (2000 2725);
FORCEPROP 2 LAST SEC_TYPE 0603
J 0
(2000 2725);
DISPLAY 1.659574 (2000 2725);
PAINT ORANGE (2000 2725);
DISPLAY INVISIBLE (2000 2725);
FORCEADD OFFPAGE..2
(2750 3200);
FORCEPROP 2 LAST $XR0 191 
J 0
(2939 3200);
DISPLAY 0.638298 (2939 3200);
PAINT MONO (2939 3200);
FORCEPROP 1 LAST COMMENT_BODY TRUE
J 0
(2705 3105);
DISPLAY 0.872340 (2705 3105);
PAINT GREEN (2705 3105);
DISPLAY INVISIBLE (2705 3105);
FORCEPROP 1 LAST OFFPAGE TRUE
J 0
(3075 3075);
DISPLAY 0.872340 (3075 3075);
PAINT GREEN (3075 3075);
DISPLAY INVISIBLE (3075 3075);
FORCEPROP 2 LAST CDS_LIB mstr_standard
J 0
(2750 3200);
PAINT ORANGE (2750 3200);
DISPLAY INVISIBLE (2750 3200);
FORCEPROP 2 LAST PATH I25
J 0
(2925 3275);
DISPLAY 1.021277 (2925 3275);
PAINT ORANGE (2925 3275);
DISPLAY INVISIBLE (2925 3275);
FORCEADD GND..1
(2175 2075);
FORCEPROP 3 LASTPIN (2175 2125) SIG_NAME GND\g
J 0
(2185 2135);
DISPLAY 0.659574 (2185 2135);
PAINT MONO (2185 2135);
DISPLAY INVISIBLE (2185 2135);
FORCEPROP 2 LAST P1V5_STBY_IBMC_VR 
J 0
(2200 2150);
PAINT GREEN (2200 2150);
FORCEPROP 2 LAST P1V5_STBY_IBMC 
J 0
(2200 2200);
PAINT GREEN (2200 2200);
FORCEPROP 1 LAST HDL_POWER GND
J 0
(2175 2225);
DISPLAY 0.872340 (2175 2225);
PAINT GREEN (2175 2225);
DISPLAY INVISIBLE (2175 2225);
FORCEPROP 1 LAST BODY_TYPE PLUMBING
J 0
(2130 2032);
DISPLAY 0.340426 (2130 2032);
PAINT GREEN (2130 2032);
DISPLAY INVISIBLE (2130 2032);
FORCEPROP 2 LAST ROOM P1V26_BMC_STBY_VR
J 0
(1825 2150);
DISPLAY 0.872340 (1825 2150);
PAINT GREEN (1825 2150);
DISPLAY INVISIBLE (1825 2150);
FORCEPROP 1 LAST VOLTAGE 0.0V
J 0
(2130 2032);
DISPLAY 0.340426 (2130 2032);
PAINT SKYBLUE (2130 2032);
DISPLAY INVISIBLE (2130 2032);
FORCEPROP 1 LAST SIZE 1B
J 0
(2250 2025);
DISPLAY 0.872340 (2250 2025);
PAINT ORANGE (2250 2025);
DISPLAY INVISIBLE (2250 2025);
FORCEPROP 2 LAST CDS_LIB mstr_symbols
J 0
(2175 2075);
PAINT ORANGE (2175 2075);
DISPLAY INVISIBLE (2175 2075);
FORCEPROP 1 LAST PATH I27
J 0
(2250 2075);
DISPLAY 0.872340 (2250 2075);
PAINT AQUA (2250 2075);
DISPLAY INVISIBLE (2250 2075);
FORCEPROP 2 LAST BOM_COST P1V26_BMC_STBY_VR
J 0
(2200 2250);
PAINT WHITE (2200 2250);
DISPLAY INVISIBLE (2200 2250);
FORCEADD GND..1
(-2000 1775);
FORCEPROP 3 LASTPIN (-2000 1825) SIG_NAME GND\g
J 0
(-1990 1835);
DISPLAY 0.659574 (-1990 1835);
PAINT MONO (-1990 1835);
DISPLAY INVISIBLE (-1990 1835);
FORCEPROP 2 LAST P1V5_STBY_IBMC 
J 0
(-1975 1900);
PAINT GREEN (-1975 1900);
FORCEPROP 2 LAST P1V5_STBY_IBMC_VR 
J 0
(-1975 1850);
PAINT GREEN (-1975 1850);
FORCEPROP 1 LAST HDL_POWER GND
J 0
(-2000 1925);
DISPLAY 0.872340 (-2000 1925);
PAINT GREEN (-2000 1925);
DISPLAY INVISIBLE (-2000 1925);
FORCEPROP 1 LAST BODY_TYPE PLUMBING
J 0
(-2045 1732);
DISPLAY 0.340426 (-2045 1732);
PAINT GREEN (-2045 1732);
DISPLAY INVISIBLE (-2045 1732);
FORCEPROP 2 LAST ROOM P1V26_BMC_STBY_VR
J 0
(-2350 1850);
DISPLAY 0.872340 (-2350 1850);
PAINT GREEN (-2350 1850);
DISPLAY INVISIBLE (-2350 1850);
FORCEPROP 1 LAST VOLTAGE 0.0V
J 0
(-2045 1732);
DISPLAY 0.340426 (-2045 1732);
PAINT SKYBLUE (-2045 1732);
DISPLAY INVISIBLE (-2045 1732);
FORCEPROP 1 LAST SIZE 1B
J 0
(-1925 1725);
DISPLAY 0.872340 (-1925 1725);
PAINT ORANGE (-1925 1725);
DISPLAY INVISIBLE (-1925 1725);
FORCEPROP 2 LAST CDS_LIB mstr_symbols
J 0
(-2000 1775);
PAINT ORANGE (-2000 1775);
DISPLAY INVISIBLE (-2000 1775);
FORCEPROP 1 LAST PATH I3
J 0
(-1925 1775);
DISPLAY 0.872340 (-1925 1775);
PAINT AQUA (-1925 1775);
DISPLAY INVISIBLE (-1925 1775);
FORCEPROP 2 LAST BOM_COST P1V26_BMC_STBY_VR
J 0
(-1975 1950);
PAINT WHITE (-1975 1950);
DISPLAY INVISIBLE (-1975 1950);
FORCEADD CAP..1
(2325 2525);
FORCEPROP 1 LAST PACK_TYPE 0805LF
J 0
(2375 2325);
DISPLAY 0.617021 (2375 2325);
PAINT SKYBLUE (2375 2325);
FORCEPROP 1 LAST PART_NUMBER C95333-002
J 0
(2375 2375);
DISPLAY 0.617021 (2375 2375);
PAINT BLUE (2375 2375);
FORCEPROP 1 LAST MATERIAL X6S
J 0
(2375 2425);
DISPLAY 0.617021 (2375 2425);
PAINT SKYBLUE (2375 2425);
FORCEPROP 1 LASTPIN (2325 2625) $PN 1
J 0
(2335 2605);
DISPLAY 0.617021 (2335 2605);
PAINT WHITE (2335 2605);
FORCEPROP 1 LAST LOCATION C9F4
J 0
(2375 2625);
DISPLAY 0.617021 (2375 2625);
PAINT AQUA (2375 2625);
FORCEPROP 1 LAST VOLTAGE 4V
J 0
(2375 2525);
DISPLAY 0.617021 (2375 2525);
PAINT SKYBLUE (2375 2525);
FORCEPROP 1 LAST TOLERANCE 20%
J 0
(2375 2475);
DISPLAY 0.617021 (2375 2475);
PAINT SKYBLUE (2375 2475);
FORCEPROP 1 LASTPIN (2325 2425) $PN 2
J 0
(2335 2405);
DISPLAY 0.617021 (2335 2405);
PAINT WHITE (2335 2405);
FORCEPROP 1 LAST VALUE 22UF
J 0
(2375 2575);
DISPLAY 0.617021 (2375 2575);
PAINT SKYBLUE (2375 2575);
FORCEPROP 2 LAST CDS_LIB mstr_discrete
J 0
(2325 2525);
PAINT ORANGE (2325 2525);
DISPLAY INVISIBLE (2325 2525);
FORCEPROP 2 LAST BOM_COST P1V26_BMC_STBY_VR
J 0
(2375 2675);
PAINT WHITE (2375 2675);
DISPLAY INVISIBLE (2375 2675);
FORCEPROP 2 LAST SEC_TYPE 0805LF
J 0
(2375 2725);
DISPLAY 1.659574 (2375 2725);
PAINT ORANGE (2375 2725);
DISPLAY INVISIBLE (2375 2725);
FORCEPROP 2 LAST SEC 1
J 0
(2375 2725);
DISPLAY 1.106383 (2375 2725);
PAINT MONO (2375 2725);
DISPLAY INVISIBLE (2375 2725);
FORCEPROP 2 LAST CDS_LOCATION C9F4
J 0
(2375 2625);
DISPLAY 0.617021 (2375 2625);
PAINT AQUA (2375 2625);
DISPLAY INVISIBLE (2375 2625);
FORCEPROP 1 LAST PATH I30
J 0
(2375 2675);
DISPLAY 0.978723 (2375 2675);
PAINT WHITE (2375 2675);
DISPLAY INVISIBLE (2375 2675);
FORCEPROP 2 LAST ROOM P1V26_BMC_STBY_VR
J 0
(2375 2725);
PAINT GREEN (2375 2725);
DISPLAY INVISIBLE (2375 2725);
FORCEADD CAP..1
(-1275 2150);
FORCEPROP 1 LAST VALUE 1.0UF
J 0
(-1225 2200);
DISPLAY 0.617021 (-1225 2200);
PAINT SKYBLUE (-1225 2200);
FORCEPROP 1 LAST LOCATION C9E11
J 0
(-1225 2250);
DISPLAY 0.617021 (-1225 2250);
PAINT AQUA (-1225 2250);
FORCEPROP 1 LAST MATERIAL X6S
J 0
(-1225 2050);
DISPLAY 0.617021 (-1225 2050);
PAINT SKYBLUE (-1225 2050);
FORCEPROP 1 LAST VOLTAGE 16V
J 0
(-1225 2150);
DISPLAY 0.617021 (-1225 2150);
PAINT SKYBLUE (-1225 2150);
FORCEPROP 1 LAST TOLERANCE 10%
J 0
(-1225 2100);
DISPLAY 0.617021 (-1225 2100);
PAINT SKYBLUE (-1225 2100);
FORCEPROP 1 LASTPIN (-1275 2250) $PN 1
J 0
(-1265 2230);
DISPLAY 0.617021 (-1265 2230);
PAINT ORANGE (-1265 2230);
FORCEPROP 1 LASTPIN (-1275 2050) $PN 2
J 0
(-1265 2030);
DISPLAY 0.617021 (-1265 2030);
PAINT ORANGE (-1265 2030);
FORCEPROP 1 LAST PACK_TYPE 0402
J 0
(-1225 1950);
DISPLAY 0.617021 (-1225 1950);
PAINT SKYBLUE (-1225 1950);
FORCEPROP 1 LAST PART_NUMBER D97712-011
J 0
(-1225 2000);
DISPLAY 0.617021 (-1225 2000);
PAINT BLUE (-1225 2000);
FORCEPROP 2 LAST CDS_LOCATION C9E11
J 0
(-1225 2250);
DISPLAY 0.617021 (-1225 2250);
PAINT AQUA (-1225 2250);
DISPLAY INVISIBLE (-1225 2250);
FORCEPROP 2 LAST CDS_LIB mstr_discrete
J 0
(-1275 2150);
PAINT MONO (-1275 2150);
DISPLAY INVISIBLE (-1275 2150);
FORCEPROP 1 LAST PATH I39
J 0
(-1225 2300);
DISPLAY 0.978723 (-1225 2300);
PAINT WHITE (-1225 2300);
DISPLAY INVISIBLE (-1225 2300);
FORCEPROP 2 LAST SEC 1
J 0
(-1225 2350);
DISPLAY 0.680851 (-1225 2350);
PAINT MONO (-1225 2350);
DISPLAY INVISIBLE (-1225 2350);
FORCEPROP 2 LAST SEC_TYPE 0402
J 0
(-1225 2350);
DISPLAY 1.021277 (-1225 2350);
PAINT ORANGE (-1225 2350);
DISPLAY INVISIBLE (-1225 2350);
FORCEADD GND..1
(-1275 1750);
FORCEPROP 3 LASTPIN (-1275 1800) SIG_NAME GND\g
J 0
(-1265 1810);
DISPLAY 0.659574 (-1265 1810);
PAINT MONO (-1265 1810);
DISPLAY INVISIBLE (-1265 1810);
FORCEPROP 1 LAST HDL_POWER GND
J 0
(-1275 1900);
DISPLAY 0.872340 (-1275 1900);
PAINT GREEN (-1275 1900);
DISPLAY INVISIBLE (-1275 1900);
FORCEPROP 1 LAST BODY_TYPE PLUMBING
J 0
(-1320 1707);
DISPLAY 0.340426 (-1320 1707);
PAINT GREEN (-1320 1707);
DISPLAY INVISIBLE (-1320 1707);
FORCEPROP 1 LAST PATH I4
J 0
(-1200 1750);
DISPLAY 0.872340 (-1200 1750);
PAINT AQUA (-1200 1750);
DISPLAY INVISIBLE (-1200 1750);
FORCEPROP 1 LAST SIZE 1B
J 0
(-1200 1700);
DISPLAY 0.872340 (-1200 1700);
PAINT AQUA (-1200 1700);
DISPLAY INVISIBLE (-1200 1700);
FORCEPROP 2 LAST CDS_LIB mstr_symbols
J 0
(-1275 1750);
PAINT ORANGE (-1275 1750);
DISPLAY INVISIBLE (-1275 1750);
FORCEPROP 1 LAST VOLTAGE 0.0V
J 0
(-1320 1707);
DISPLAY 0.340426 (-1320 1707);
PAINT SKYBLUE (-1320 1707);
DISPLAY INVISIBLE (-1320 1707);
FORCEADD RT9059..1
(-175 2700);
FORCEPROP 2 LASTPIN (-675 2500) $PN 6
J 2
(-685 2510);
DISPLAY 0.617021 (-685 2510);
PAINT ORANGE (-685 2510);
FORCEPROP 2 LASTPIN (-675 2750) $PN 9
J 2
(-685 2760);
DISPLAY 0.617021 (-685 2760);
PAINT ORANGE (-685 2760);
FORCEPROP 2 LASTPIN (-675 2700) $PN 8
J 2
(-685 2710);
DISPLAY 0.617021 (-685 2710);
PAINT ORANGE (-685 2710);
FORCEPROP 2 LASTPIN (-675 2650) $PN 7
J 2
(-685 2660);
DISPLAY 0.617021 (-685 2660);
PAINT ORANGE (-685 2660);
FORCEPROP 2 LASTPIN (-675 2900) $PN 10
J 2
(-685 2910);
DISPLAY 0.617021 (-685 2910);
PAINT ORANGE (-685 2910);
FORCEPROP 1 LAST LOCATION EU9F1
J 0
(-625 3150);
DISPLAY 0.617021 (-625 3150);
PAINT AQUA (-625 3150);
FORCEPROP 2 LASTPIN (325 2500) $PN 4
J 0
(335 2510);
DISPLAY 0.617021 (335 2510);
PAINT ORANGE (335 2510);
FORCEPROP 2 LASTPIN (325 2400) $PN 11
J 0
(335 2410);
DISPLAY 0.617021 (335 2410);
PAINT ORANGE (335 2410);
FORCEPROP 2 LASTPIN (325 2900) $PN 5
J 0
(335 2910);
DISPLAY 0.617021 (335 2910);
PAINT ORANGE (335 2910);
FORCEPROP 2 LASTPIN (325 2650) $PN 1
J 0
(335 2660);
DISPLAY 0.617021 (335 2660);
PAINT ORANGE (335 2660);
FORCEPROP 2 LASTPIN (325 2700) $PN 2
J 0
(335 2710);
DISPLAY 0.617021 (335 2710);
PAINT ORANGE (335 2710);
FORCEPROP 2 LASTPIN (325 2750) $PN 3
J 0
(335 2760);
DISPLAY 0.617021 (335 2760);
PAINT ORANGE (335 2760);
FORCEPROP 1 LAST MATERIAL IC
J 0
(-625 3100);
DISPLAY 0.617021 (-625 3100);
PAINT SKYBLUE (-625 3100);
FORCEPROP 1 LAST PART_NUMBER H65765-001
J 0
(-625 2300);
DISPLAY 0.617021 (-625 2300);
PAINT BLUE (-625 2300);
FORCEPROP 2 LAST CDS_LIB mstr_vreg
J 0
(-175 2700);
PAINT MONO (-175 2700);
DISPLAY INVISIBLE (-175 2700);
FORCEPROP 0 LAST ROOM P1V26_BMC_STBY_VR
J 0
(-625 3250);
DISPLAY 1.021277 (-625 3250);
PAINT ORANGE (-625 3250);
DISPLAY INVISIBLE (-625 3250);
FORCEPROP 1 LAST PATH I40
J 0
(-125 3100);
PAINT GREEN (-125 3100);
DISPLAY INVISIBLE (-125 3100);
FORCEPROP 2 LAST CDS_LOCATION EU9F1
J 0
(-625 3150);
DISPLAY 0.617021 (-625 3150);
PAINT AQUA (-625 3150);
DISPLAY INVISIBLE (-625 3150);
FORCEPROP 2 LAST SEC 1
J 0
(-625 3200);
DISPLAY 0.680851 (-625 3200);
PAINT MONO (-625 3200);
DISPLAY INVISIBLE (-625 3200);
FORCEPROP 2 LAST SEC_TYPE DFN
J 0
(-625 3200);
DISPLAY 1.021277 (-625 3200);
PAINT ORANGE (-625 3200);
DISPLAY INVISIBLE (-625 3200);
FORCEPROP 1 LAST PACK_TYPE DFN
J 0
(-625 3200);
PAINT SKYBLUE (-625 3200);
DISPLAY INVISIBLE (-625 3200);
FORCEADD RES..1
(1850 3200);
FORCEPROP 1 LAST WATTAGE 1/16W
J 2
(1825 3050);
DISPLAY 0.617021 (1825 3050);
PAINT SKYBLUE (1825 3050);
FORCEPROP 1 LAST MATERIAL CHIP
J 0
(1850 3050);
DISPLAY 0.617021 (1850 3050);
PAINT SKYBLUE (1850 3050);
FORCEPROP 1 LASTPIN (1750 3200) $PN 1
J 0
(1762 3212);
DISPLAY 0.617021 (1762 3212);
PAINT ORANGE (1762 3212);
FORCEPROP 1 LAST VALUE 22.1
J 2
(1825 3100);
DISPLAY 0.617021 (1825 3100);
PAINT SKYBLUE (1825 3100);
FORCEPROP 1 LASTPIN (1950 3200) $PN 2
J 0
(1912 3212);
DISPLAY 0.617021 (1912 3212);
PAINT ORANGE (1912 3212);
FORCEPROP 1 LAST TOLERANCE 1.0%
J 0
(1850 3100);
DISPLAY 0.617021 (1850 3100);
PAINT SKYBLUE (1850 3100);
FORCEPROP 1 LAST LOCATION R9F11
J 0
(1800 3250);
DISPLAY 0.617021 (1800 3250);
PAINT AQUA (1800 3250);
FORCEPROP 1 LAST PART_NUMBER G21796-250
J 0
(1800 3300);
DISPLAY 0.617021 (1800 3300);
PAINT BLUE (1800 3300);
FORCEPROP 1 LAST PACK_TYPE 0402
J 0
(2100 3050);
DISPLAY 0.617021 (2100 3050);
PAINT SKYBLUE (2100 3050);
FORCEPROP 2 LAST CDS_LIB mstr_discrete
J 0
(1850 3200);
PAINT MONO (1850 3200);
DISPLAY INVISIBLE (1850 3200);
FORCEPROP 2 LAST CDS_LOCATION R9F11
J 0
(1800 3250);
DISPLAY 0.617021 (1800 3250);
PAINT AQUA (1800 3250);
DISPLAY INVISIBLE (1800 3250);
FORCEPROP 2 LAST SEC_TYPE 0402
J 0
(1800 3400);
DISPLAY 1.021277 (1800 3400);
PAINT ORANGE (1800 3400);
DISPLAY INVISIBLE (1800 3400);
FORCEPROP 2 LAST SEC 1
J 0
(1800 3400);
DISPLAY 0.680851 (1800 3400);
PAINT MONO (1800 3400);
DISPLAY INVISIBLE (1800 3400);
FORCEPROP 0 LAST ROOM P1V26_BMC_STBY_VR
J 0
(1800 3400);
DISPLAY 1.021277 (1800 3400);
PAINT ORANGE (1800 3400);
DISPLAY INVISIBLE (1800 3400);
FORCEPROP 1 LAST PATH I41
J 0
(1800 3350);
DISPLAY 0.978723 (1800 3350);
PAINT WHITE (1800 3350);
DISPLAY INVISIBLE (1800 3350);
FORCEADD P3V3_STBY..1
(-1275 3075);
FORCEPROP 3 LASTPIN (-1275 3025) SIG_NAME P3V3_STBY\g
J 0
(-1265 3035);
DISPLAY 0.659574 (-1265 3035);
PAINT MONO (-1265 3035);
DISPLAY INVISIBLE (-1265 3035);
FORCEPROP 1 LAST HDL_POWER P3V3_STBY
J 0
(-1575 2950);
DISPLAY 0.872340 (-1575 2950);
PAINT ORANGE (-1575 2950);
DISPLAY INVISIBLE (-1575 2950);
FORCEPROP 1 LAST BODY_TYPE PLUMBING
J 0
(-1320 3032);
DISPLAY 0.340426 (-1320 3032);
PAINT GREEN (-1320 3032);
DISPLAY INVISIBLE (-1320 3032);
FORCEPROP 1 LAST VOLTAGE 3.3V
J 0
(-1320 3032);
DISPLAY 0.340426 (-1320 3032);
PAINT SKYBLUE (-1320 3032);
DISPLAY INVISIBLE (-1320 3032);
FORCEPROP 1 LAST PATH I42
J 0
(-1230 3077);
DISPLAY 0.340426 (-1230 3077);
PAINT GREEN (-1230 3077);
DISPLAY INVISIBLE (-1230 3077);
FORCEPROP 2 LAST CDS_LIB mstr_symbols
J 0
(-1275 3075);
PAINT ORANGE (-1275 3075);
DISPLAY INVISIBLE (-1275 3075);
FORCEPROP 1 LAST SIZE 1B
J 0
(-1230 3097);
DISPLAY 0.340426 (-1230 3097);
PAINT GREEN (-1230 3097);
DISPLAY INVISIBLE (-1230 3097);
FORCEADD W_VCC_CIRCLE..1
(2325 2825);
FORCEPROP 3 LASTPIN (2325 2825) SIG_NAME P1V15_AUX_BMC\g
J 0
(2335 2835);
DISPLAY 0.659574 (2335 2835);
PAINT MONO (2335 2835);
DISPLAY INVISIBLE (2335 2835);
FORCEPROP 1 LAST HDL_POWER P1V15_AUX_BMC
J 1
(2346 2900);
DISPLAY 0.872340 (2346 2900);
PAINT ORANGE (2346 2900);
FORCEPROP 1 LAST BODY_TYPE PLUMBING
J 0
(2337 2819);
DISPLAY 0.340426 (2337 2819);
PAINT GREEN (2337 2819);
DISPLAY INVISIBLE (2337 2819);
FORCEPROP 2 LAST CDS_LIB w_power
J 0
(2325 2825);
PAINT MONO (2325 2825);
DISPLAY INVISIBLE (2325 2825);
FORCEPROP 1 LAST PATH I43
J 0
(2325 2825);
DISPLAY 0.617021 (2325 2825);
PAINT GREEN (2325 2825);
DISPLAY INVISIBLE (2325 2825);
FORCEPROP 1 LAST CDS_LMAN_SYM_OUTLINE -100,100,100,-100
J 0
(2325 2825);
DISPLAY 0.468085 (2325 2825);
PAINT GREEN (2325 2825);
DISPLAY INVISIBLE (2325 2825);
FORCEADD P3V3_STBY..1
(-1875 3550);
FORCEPROP 3 LASTPIN (-1875 3500) SIG_NAME P3V3_STBY\g
J 0
(-1865 3510);
DISPLAY 0.659574 (-1865 3510);
PAINT MONO (-1865 3510);
DISPLAY INVISIBLE (-1865 3510);
FORCEPROP 1 LAST HDL_POWER P3V3_STBY
J 0
(-2175 3425);
DISPLAY 0.872340 (-2175 3425);
PAINT ORANGE (-2175 3425);
DISPLAY INVISIBLE (-2175 3425);
FORCEPROP 1 LAST BODY_TYPE PLUMBING
J 0
(-1920 3507);
DISPLAY 0.340426 (-1920 3507);
PAINT GREEN (-1920 3507);
DISPLAY INVISIBLE (-1920 3507);
FORCEPROP 1 LAST SIZE 1B
J 0
(-1830 3572);
DISPLAY 0.340426 (-1830 3572);
PAINT GREEN (-1830 3572);
DISPLAY INVISIBLE (-1830 3572);
FORCEPROP 1 LAST VOLTAGE 3.3V
J 0
(-1920 3507);
DISPLAY 0.340426 (-1920 3507);
PAINT SKYBLUE (-1920 3507);
DISPLAY INVISIBLE (-1920 3507);
FORCEPROP 1 LAST PATH I44
J 0
(-1830 3552);
DISPLAY 0.340426 (-1830 3552);
PAINT GREEN (-1830 3552);
DISPLAY INVISIBLE (-1830 3552);
FORCEPROP 2 LAST CDS_LIB mstr_symbols
J 0
(-1875 3550);
PAINT MONO (-1875 3550);
DISPLAY INVISIBLE (-1875 3550);
FORCEADD 4K42R2F-GP..1
(1025 2475);
FORCEPROP 1 LAST LOCATION R9F6
J 0
(1045 2555);
DISPLAY 0.617021 (1045 2555);
PAINT GREEN (1045 2555);
FORCEPROP 1 LAST VALUE 4K42R2F-GP
J 0
(1045 2375);
DISPLAY 0.617021 (1045 2375);
PAINT GREEN (1045 2375);
FORCEPROP 1 LAST CDS_LMAN_SYM_OUTLINE -50,75,50,-75
J 0
(1025 2475);
DISPLAY 0.468085 (1025 2475);
PAINT GREEN (1025 2475);
DISPLAY INVISIBLE (1025 2475);
FORCEPROP 1 LAST PATH I45
J 0
(1025 2475);
DISPLAY 0.617021 (1025 2475);
PAINT GREEN (1025 2475);
DISPLAY INVISIBLE (1025 2475);
FORCEPROP 2 LAST CDS_LIB w_hdl
J 0
(1025 2475);
PAINT MONO (1025 2475);
DISPLAY INVISIBLE (1025 2475);
FORCEPROP 1 LAST PART_NUMBER 64.44215.6DL
J 0
(1025 2475);
DISPLAY 0.617021 (1025 2475);
PAINT GREEN (1025 2475);
DISPLAY INVISIBLE (1025 2475);
FORCEPROP 1 LAST PACK_TYPE SMD-RG
J 0
(1025 2475);
DISPLAY 0.617021 (1025 2475);
PAINT GREEN (1025 2475);
DISPLAY INVISIBLE (1025 2475);
FORCEADD CAP..1
R 2
(-2000 2175);
FORCEPROP 1 LAST VOLTAGE 50V
J 2
(-2050 2175);
DISPLAY 0.617021 (-2050 2175);
PAINT SKYBLUE (-2050 2175);
FORCEPROP 1 LAST PACK_TYPE 0402LF
J 2
(-2175 2125);
DISPLAY 0.617021 (-2175 2125);
PAINT SKYBLUE (-2175 2125);
FORCEPROP 1 LAST VALUE 1000PF
J 2
(-2150 2200);
DISPLAY 0.617021 (-2150 2200);
PAINT SKYBLUE (-2150 2200);
FORCEPROP 1 LAST LOCATION C9F9
J 2
(-2175 2250);
DISPLAY 0.617021 (-2175 2250);
PAINT AQUA (-2175 2250);
FORCEPROP 1 LAST MATERIAL EMPTY
J 2
(-2050 2075);
DISPLAY 0.617021 (-2050 2075);
PAINT RED (-2050 2075);
FORCEPROP 1 LAST TOLERANCE 10%
J 2
(-2050 2125);
DISPLAY 0.617021 (-2050 2125);
PAINT SKYBLUE (-2050 2125);
FORCEPROP 1 LASTPIN (-2000 2075) $PN 2
J 2
(-2010 2055);
DISPLAY 0.617021 (-2010 2055);
PAINT WHITE (-2010 2055);
FORCEPROP 1 LASTPIN (-2000 2275) $PN 1
J 2
(-2010 2255);
DISPLAY 0.617021 (-2010 2255);
PAINT WHITE (-2010 2255);
FORCEPROP 1 LAST PART_NUMBER A36096-046
J 2
(-2050 2025);
DISPLAY 0.617021 (-2050 2025);
PAINT BLUE (-2050 2025);
FORCEPROP 2 LAST CDS_LOCATION C9F9
J 2
(-2175 2250);
DISPLAY 0.617021 (-2175 2250);
PAINT AQUA (-2175 2250);
DISPLAY INVISIBLE (-2175 2250);
FORCEPROP 2 LAST ROOM P1V26_BMC_STBY_VR
J 2
(-2050 2300);
DISPLAY 1.212766 (-2050 2300);
PAINT GREEN (-2050 2300);
DISPLAY INVISIBLE (-2050 2300);
FORCEPROP 2 LAST BOM_COST P1V26_BMC_STBY_VR
J 0
(-2065 2285);
DISPLAY 1.617021 (-2065 2285);
PAINT WHITE (-2065 2285);
DISPLAY INVISIBLE (-2065 2285);
FORCEPROP 1 LAST PATH I5
J 2
(-2050 2325);
DISPLAY 0.978723 (-2050 2325);
PAINT WHITE (-2050 2325);
DISPLAY INVISIBLE (-2050 2325);
FORCEPROP 2 LAST CDS_LIB mstr_discrete
J 0
(-2000 2175);
DISPLAY 1.617021 (-2000 2175);
PAINT MONO (-2000 2175);
DISPLAY INVISIBLE (-2000 2175);
FORCEPROP 2 LAST $SEC 1
J 0
(-2040 2385);
DISPLAY 1.617021 (-2040 2385);
PAINT MONO (-2040 2385);
DISPLAY INVISIBLE (-2040 2385);
FORCEPROP 2 LAST CDS_SEC 1
J 0
(-2040 2385);
DISPLAY 1.617021 (-2040 2385);
PAINT MONO (-2040 2385);
DISPLAY INVISIBLE (-2040 2385);
FORCEADD GND..1
(-1875 2775);
FORCEPROP 3 LASTPIN (-1875 2825) SIG_NAME GND\g
J 0
(-1865 2835);
DISPLAY 0.659574 (-1865 2835);
PAINT MONO (-1865 2835);
DISPLAY INVISIBLE (-1865 2835);
FORCEPROP 1 LAST HDL_POWER GND
J 0
(-1875 2925);
DISPLAY 0.872340 (-1875 2925);
PAINT GREEN (-1875 2925);
DISPLAY INVISIBLE (-1875 2925);
FORCEPROP 1 LAST BODY_TYPE PLUMBING
J 0
(-1920 2732);
DISPLAY 0.340426 (-1920 2732);
PAINT GREEN (-1920 2732);
DISPLAY INVISIBLE (-1920 2732);
FORCEPROP 1 LAST PATH I6
J 0
(-1800 2775);
DISPLAY 0.872340 (-1800 2775);
PAINT AQUA (-1800 2775);
DISPLAY INVISIBLE (-1800 2775);
FORCEPROP 1 LAST VOLTAGE 0.0V
J 0
(-1920 2732);
DISPLAY 0.340426 (-1920 2732);
PAINT SKYBLUE (-1920 2732);
DISPLAY INVISIBLE (-1920 2732);
FORCEPROP 1 LAST SIZE 1B
J 0
(-1800 2725);
DISPLAY 0.872340 (-1800 2725);
PAINT AQUA (-1800 2725);
DISPLAY INVISIBLE (-1800 2725);
FORCEPROP 2 LAST CDS_LIB mstr_symbols
J 0
(-1875 2775);
PAINT ORANGE (-1875 2775);
DISPLAY INVISIBLE (-1875 2775);
FORCEADD CAP..1
(-1875 3025);
FORCEPROP 1 LASTPIN (-1875 2925) $PN 2
J 0
(-1865 2905);
DISPLAY 0.617021 (-1865 2905);
PAINT WHITE (-1865 2905);
FORCEPROP 1 LAST TOLERANCE 20%
J 0
(-1825 2975);
DISPLAY 0.617021 (-1825 2975);
PAINT SKYBLUE (-1825 2975);
FORCEPROP 1 LAST PACK_TYPE 0603
J 0
(-1825 2825);
DISPLAY 0.617021 (-1825 2825);
PAINT SKYBLUE (-1825 2825);
FORCEPROP 1 LAST VOLTAGE 6.3V
J 0
(-1825 3025);
DISPLAY 0.617021 (-1825 3025);
PAINT SKYBLUE (-1825 3025);
FORCEPROP 1 LAST MATERIAL X6S
J 0
(-1825 2925);
DISPLAY 0.617021 (-1825 2925);
PAINT SKYBLUE (-1825 2925);
FORCEPROP 1 LAST PART_NUMBER E15431-002
J 0
(-1825 2875);
DISPLAY 0.617021 (-1825 2875);
PAINT BLUE (-1825 2875);
FORCEPROP 1 LASTPIN (-1875 3125) $PN 1
J 0
(-1865 3105);
DISPLAY 0.617021 (-1865 3105);
PAINT WHITE (-1865 3105);
FORCEPROP 1 LAST VALUE 10UF
J 0
(-1825 3075);
DISPLAY 0.617021 (-1825 3075);
PAINT SKYBLUE (-1825 3075);
FORCEPROP 1 LAST LOCATION C9F3
J 0
(-1825 3125);
DISPLAY 0.617021 (-1825 3125);
PAINT AQUA (-1825 3125);
FORCEPROP 2 LAST CDS_LIB mstr_discrete
J 0
(-1875 3025);
PAINT ORANGE (-1875 3025);
DISPLAY INVISIBLE (-1875 3025);
FORCEPROP 2 LAST BOM_COST P1V26_BMC_STBY_VR
J 0
(-2000 3175);
PAINT WHITE (-2000 3175);
DISPLAY INVISIBLE (-2000 3175);
FORCEPROP 2 LAST CDS_LOCATION C9F3
J 0
(-1825 3125);
DISPLAY 0.617021 (-1825 3125);
PAINT AQUA (-1825 3125);
DISPLAY INVISIBLE (-1825 3125);
FORCEPROP 1 LAST PATH I7
J 0
(-1825 3175);
DISPLAY 0.978723 (-1825 3175);
PAINT WHITE (-1825 3175);
DISPLAY INVISIBLE (-1825 3175);
FORCEPROP 2 LAST ROOM P1V26_BMC_STBY_VR
J 0
(-1825 3175);
DISPLAY 0.723404 (-1825 3175);
PAINT GREEN (-1825 3175);
DISPLAY INVISIBLE (-1825 3175);
FORCEPROP 2 LAST SEC_TYPE 0603
J 0
(-1825 3225);
DISPLAY 1.659574 (-1825 3225);
PAINT ORANGE (-1825 3225);
DISPLAY INVISIBLE (-1825 3225);
FORCEPROP 2 LAST SEC 1
J 0
(-1825 3225);
DISPLAY 1.106383 (-1825 3225);
PAINT MONO (-1825 3225);
DISPLAY INVISIBLE (-1825 3225);
FORCEADD CAD_NOTE..1
(-2350 3125);
FORCEPROP 0 LAST L1 MUST PLACE
J 0
(-2500 3025);
DISPLAY 0.744681 (-2500 3025);
PAINT WHITE (-2500 3025);
FORCEPROP 0 LAST L2 NEXT TO INPUT PIN
J 0
(-2500 2975);
DISPLAY 0.744681 (-2500 2975);
PAINT WHITE (-2500 2975);
FORCEPROP 1 LAST COMMENT_BODY TRUE
J 0
(-2325 3225);
DISPLAY 2.212766 (-2325 3225);
PAINT PEACH (-2325 3225);
DISPLAY INVISIBLE (-2325 3225);
FORCEPROP 2 LAST ROOM P1V26_BMC_STBY_VR
J 0
(-2500 3075);
DISPLAY 1.659574 (-2500 3075);
PAINT GREEN (-2500 3075);
DISPLAY INVISIBLE (-2500 3075);
FORCEPROP 2 LAST CDS_LIB mstr_symbols
J 0
(-2350 3125);
DISPLAY 1.617021 (-2350 3125);
PAINT WHITE (-2350 3125);
DISPLAY INVISIBLE (-2350 3125);
FORCEADD DESIGN_NOTE..1
(2925 3800);
FORCEPROP 1 LAST COMMENT_BODY TRUE
J 0
(2950 3900);
DISPLAY 1.361702 (2950 3900);
PAINT WHITE (2950 3900);
DISPLAY INVISIBLE (2950 3900);
FORCEPROP 2 LAST CDS_LIB mstr_symbols
J 0
(2925 3800);
PAINT ORANGE (2925 3800);
DISPLAY INVISIBLE (2925 3800);
FORCEADD DNS..2
(-1995 2170);
PAINT RED (-1995 2170);
FORCEPROP 1 LAST COMMENT_BODY TRUE
R 1
J 0
(-1920 1945);
DISPLAY 0.872340 (-1920 1945);
PAINT GREEN (-1920 1945);
DISPLAY INVISIBLE (-1920 1945);
FORCEPROP 2 LAST CDS_LIB mstr_misc
J 0
(-1995 2170);
PAINT ORANGE (-1995 2170);
DISPLAY INVISIBLE (-1995 2170);
FORCEADD INTEL_CORP_BPAGE..1
(4250 200);
FORCEPROP 1 LAST CDS_CON_LAST_MODIFIED Tue Dec 01 11:52:31 2015
J 0
(2825 525);
PAINT ORANGE (2825 525);
DISPLAY INVISIBLE (2825 525);
FORCEPROP 1 LAST CUSTOM_TXT_CDS <CURRENT_DESIGN_SHEET> OF <TOTAL_DESIGN_SHEETS>
J 0
(3750 225);
PAINT GREEN (3750 225);
FORCEPROP 1 LAST CUSTOM_TXT_CDS <CON_LAST_MODIFIED>
J 0
(2325 550);
PAINT GREEN (2325 550);
FORCEPROP 2 LAST CUSTOM_TXT_CDS <XR_PAGE_TITLE>
J 0
(-3640 5450);
DISPLAY 0.638298 (-3640 5450);
PAINT PINK (-3640 5450);
DISPLAY INVISIBLE (-3640 5450);
FORCEPROP 1 LAST SCH_NUMBER H4694802
J 0
(2950 350);
DISPLAY 1.212766 (2950 350);
PAINT YELLOW (2950 350);
FORCEPROP 1 LAST SCH_ADDRESS2 P.O. BOX 58119
J 0
(275 275);
DISPLAY 0.617021 (275 275);
PAINT GREEN (275 275);
FORCEPROP 1 LAST SCH_ADDRESS3 Santa Clara, CA 95052-8119
J 0
(275 225);
DISPLAY 0.617021 (275 225);
PAINT GREEN (275 225);
FORCEPROP 1 LAST SCH_ADDRESS1 2200 Mission College Blvd.
J 0
(275 325);
DISPLAY 0.617021 (275 325);
PAINT GREEN (275 325);
FORCEPROP 1 LAST SCH_DEPT BESD
J 1
(-200 300);
DISPLAY 1.212766 (-200 300);
PAINT YELLOW (-200 300);
FORCEPROP 1 LAST SCH_REV 2.420
J 0
(4000 350);
DISPLAY 0.978723 (4000 350);
PAINT YELLOW (4000 350);
FORCEPROP 1 LAST SCH_TITLE P1V15 BMC STBY VR
J 0
(-3700 250);
DISPLAY 1.212766 (-3700 250);
PAINT ORANGE (-3700 250);
FORCEPROP 1 LAST COMMENT_BODY TRUE
J 0
(4262 212);
DISPLAY 0.468085 (4262 212);
PAINT GREEN (4262 212);
DISPLAY INVISIBLE (4262 212);
FORCEPROP 2 LAST PAGE_BORDER TRUE
J 0
(-3640 5450);
DISPLAY 0.638298 (-3640 5450);
PAINT PINK (-3640 5450);
DISPLAY INVISIBLE (-3640 5450);
FORCEPROP 2 LAST CDS_LIB mstr_symbols
J 0
(4250 200);
PAINT MONO (4250 200);
DISPLAY INVISIBLE (4250 200);
FORCEPROP 2 LAST CDS_XR_PAGE_TITLE CR-238 : @BASEBOARD_FAB2_LIB.BASEBOARD_FAB2(SCH_1):PAGE238
J 0
(-3640 5450);
DISPLAY 0.638298 (-3640 5450);
PAINT PINK (-3640 5450);
DISPLAY INVISIBLE (-3640 5450);
WIRE 16 -1 (1025 2000)(1025 1900);
WIRE 16 -1 (325 2400)(400 2400);
WIRE 16 -1 (400 2250)(400 2400);
WIRE 16 -1 (1250 2875)(1250 2950);
WIRE 16 -1 (900 3600)(900 3775);
WIRE 16 -1 (2325 2425)(2325 2250);
WIRE 16 -1 (2175 2250)(2325 2250);
WIRE 16 -1 (1950 2250)(2175 2250);
WIRE 16 -1 (2175 2125)(2175 2250);
WIRE 16 -1 (1950 2250)(1950 2425);
WIRE 16 -1 (-2000 2075)(-2000 1825);
WIRE 16 -1 (-1275 1800)(-1275 2050);
WIRE 16 -1 (-1275 2900)(-675 2900);
WIRE 16 -1 (-1275 3025)(-1275 2900);
WIRE 16 -1 (-1275 2250)(-1275 2900);
WIRE 16 -1 (325 2650)(550 2650);
WIRE 16 -1 (550 2650)(550 2700);
WIRE 16 -1 (550 2750)(550 2700);
WIRE 16 -1 (550 2700)(325 2700);
WIRE 16 -1 (325 2750)(550 2750);
WIRE 16 -1 (550 2750)(1025 2750);
WIRE 16 -1 (1025 2600)(1025 2750);
WIRE 16 -1 (1025 2750)(1950 2750);
WIRE 16 -1 (1950 2750)(2325 2750);
FORCEPROP 0 LAST VOLTAGE 1.5
J 0
(2200 2800);
PAINT SKYBLUE (2200 2800);
DISPLAY INVISIBLE (2200 2800);
WIRE 16 -1 (1950 2750)(1950 2625);
WIRE 16 -1 (2325 2625)(2325 2750);
WIRE 16 -1 (2325 2750)(2325 2825);
WIRE 16 -1 (-1050 2650)(-675 2650);
WIRE 16 -1 (-1050 2700)(-1050 2650);
WIRE 16 -1 (-1050 2700)(-675 2700);
WIRE 16 -1 (-1050 2700)(-1050 2750);
WIRE 16 -1 (-1050 2750)(-675 2750);
WIRE 16 -1 (-1050 3200)(-1050 2750);
WIRE 16 -1 (-1875 3200)(-1050 3200);
WIRE 16 -1 (-1875 3125)(-1875 3200);
WIRE 16 -1 (-1875 3500)(-1875 3200);
FORCEPROP 0 LAST VOLTAGE 3.3 V
J 0
(-1875 3375);
PAINT SKYBLUE (-1875 3375);
DISPLAY INVISIBLE (-1875 3375);
WIRE 16 -1 (-1875 2925)(-1875 2825);
WIRE 16 -1 (-2575 2500)(-2000 2500);
FORCEPROP 2 LAST SIG_NAME PWRGD_P1V538_BMC_STBY
J 0
(-2560 2510);
DISPLAY 0.617021 (-2560 2510);
PAINT ORANGE (-2560 2510);
WIRE 16 -1 (-675 2500)(-2000 2500);
WIRE 16 -1 (-2000 2275)(-2000 2500);
WIRE 16 2175 (-1625 3225)(-1625 2875);
WIRE 16 2175 (-2575 3225)(-1625 3225);
WIRE 16 2175 (-1625 2875)(-2575 2875);
WIRE 16 2175 (-2575 2875)(-2575 3225);
WIRE 16 -1 (1950 3200)(2700 3200);
FORCEPROP 2 LAST SIG_NAME PWRGD_P1V26_BMC_STBY
J 0
(2066 3210);
DISPLAY 0.617021 (2066 3210);
PAINT ORANGE (2066 3210);
WIRE 16 -1 (1250 3150)(1250 3200);
WIRE 16 -1 (1250 3200)(1750 3200);
WIRE 16 -1 (900 3200)(1250 3200);
FORCEPROP 2 LAST SIG_NAME PWRGD_P1V26_BMC_STBY_R
J 0
(966 3210);
DISPLAY 0.617021 (966 3210);
PAINT ORANGE (966 3210);
FORCEPROP 2 LASTPROP $XRERR UNIQUE?
J 0
(726 3210);
DISPLAY 0.638298 (726 3210);
PAINT MONO (726 3210);
DISPLAY INVISIBLE (726 3210);
WIRE 16 -1 (900 3200)(900 3400);
WIRE 16 -1 (700 3200)(900 3200);
WIRE 16 -1 (700 2900)(700 3200);
WIRE 16 -1 (325 2900)(700 2900);
WIRE 3 2175 (1550 3000)(3325 3000);
WIRE 3 2175 (1550 3000)(1550 2700);
WIRE 3 2175 (3325 3000)(3325 2700);
WIRE 3 2175 (1550 2700)(3325 2700);
WIRE 3 2175 (950 2650)(1300 2650);
WIRE 3 2175 (950 2650)(950 2300);
WIRE 3 2175 (1300 2650)(1300 2300);
WIRE 3 2175 (950 2300)(1300 2300);
WIRE 16 -1 (1025 2200)(1025 2250);
WIRE 16 -1 (1025 2250)(1025 2350);
WIRE 16 -1 (875 2250)(1025 2250);
WIRE 16 -1 (875 2500)(875 2250);
WIRE 16 -1 (325 2500)(875 2500);
FORCEPROP 2 LAST SIG_NAME VR_P1V26_BMC_STBY_FB
J 0
(390 2510);
DISPLAY 0.617021 (390 2510);
PAINT ORANGE (390 2510);
FORCEPROP 2 LASTPROP $XRERR UNIQUE?
J 0
(150 2510);
DISPLAY 0.638298 (150 2510);
PAINT MONO (150 2510);
DISPLAY INVISIBLE (150 2510);
DOT 1 (-2000 2500);
DOT 1 (-1275 2900);
DOT 1 (-1050 2700);
DOT 1 (-1050 2750);
DOT 1 (-1875 3200);
DOT 1 (550 2700);
DOT 1 (550 2750);
DOT 1 (1025 2750);
DOT 1 (1950 2750);
DOT 1 (1250 3200);
DOT 1 (2325 2750);
DOT 1 (2175 2250);
DOT 1 (900 3200);
DOT 1 (1025 2250);
FORCENOTE
IOUT=752MA
(2725 3575) 0;
DISPLAY LEFT (2725 3575);
DISPLAY 1.021277 (2725 3575);
PAINT PURPLE (2725 3575);
FORCENOTE
VOUT=1.26V
(2725 3650) 0;
DISPLAY LEFT (2725 3650);
DISPLAY 1.021277 (2725 3650);
PAINT PURPLE (2725 3650);
FORCENOTE
TP FAB1 CHANGE POWER RAIL FOR BMC 1120
(2625 2600) 0;
DISPLAY LEFT (2625 2600);
DISPLAY 0.851064 (2625 2600);
PAINT RED (2625 2600);
FORCENOTE
TP FAB1 CHANGE R9F6 FOR 1.15V POWER RAIL 1123
(1350 1950) 0;
DISPLAY LEFT (1350 1950);
DISPLAY 0.851064 (1350 1950);
PAINT RED (1350 1950);
QUIT
